FILE_TYPE=LIBRARY_PARTS;
TIME=' Created/Modified on Mon Feb 23 13:35:10 2009' ;
primitive 'Q_SHORT';
  pin
    '1':
      PIN_NUMBER='(1)';
      INPUT_LOAD='(-0.01,0.01)';
      OUTPUT_LOAD='(1.0,-1.0)';
      BIDIRECTIONAL='TRUE';
    '2':
      PIN_NUMBER='(2)';
      INPUT_LOAD='(-0.01,0.01)';
      OUTPUT_LOAD='(1.0,-1.0)';
      BIDIRECTIONAL='TRUE';
  end_pin;
  body
    CLASS='IO';
    PART_NAME='Q_SHORT';
    PHYS_DES_PREFIX='J';
  end_body;
end_primitive;
END.
